(kicad_pcb
	(version 20221018)
	(generator pcbnew)
	(general
    (thickness 1.518)
  )
	(paper "A4")
	(title_block
    (title "Kria K26 Devboard")
    (date "2024-03-26")
    (rev "1.2.5")
    (comment 1 "www.antmicro.com")
    (comment 2 "Antmicro Ltd.")
		(comment 9 "footprints 515-524 of 660")
	)
	(layers
    (0 "F.Cu" mixed)
    (1 "In1.Cu" power)
    (2 "In2.Cu" mixed)
    (3 "In3.Cu" power)
    (4 "In4.Cu" mixed)
    (5 "In5.Cu" power)
    (6 "In6.Cu" mixed)
    (31 "B.Cu" power)
    (32 "B.Adhes" user "B.Adhesive")
    (33 "F.Adhes" user "F.Adhesive")
    (34 "B.Paste" user)
    (35 "F.Paste" user)
    (36 "B.SilkS" user "B.Silkscreen")
    (37 "F.SilkS" user "F.Silkscreen")
    (38 "B.Mask" user)
    (39 "F.Mask" user)
    (40 "Dwgs.User" user "User.Drawings")
    (41 "Cmts.User" user "User.Comments")
    (42 "Eco1.User" user "User.Eco1")
    (43 "Eco2.User" user "User.Eco2")
    (44 "Edge.Cuts" user)
    (45 "Margin" user)
    (46 "B.CrtYd" user "B.Courtyard")
    (47 "F.CrtYd" user "F.Courtyard")
    (48 "B.Fab" user)
    (49 "F.Fab" user)
  )
	(footprint "kria-k26-devboard-footprints:C_0402_1005Metric" (layer "B.Cu")
    (at 124.1 146.535 -90)
    (descr "Capacitor SMD 0402")
    (tags "capacitor SMD 0402")
    (property "Author" "Antmicro")
    (property "Dielectric" "")
    (property "License" "Apache-2.0")
    (property "MPN" "C1005X5R1E474M050BB")
    (property "Manufacturer" "TDK")
    (property "Sheetfile" "sd-3-card.kicad_sch")
    (property "Sheetname" "SD 3.0 card")
    (property "Val" "470n")
    (property "Voltage" "")
    (property "ki_description" " ")
    (attr smd)
    (fp_text reference "C17" (at 0.871 -0.41 90) (layer "B.SilkS")
        (effects (font (size 0.7 0.7) (thickness 0.15)) (justify left bottom mirror))
    )
    (fp_text value "C_470n_0402" (at 0 -1.4 90) (layer "B.Fab") hide
        (effects (font (size 0.7 0.7) (thickness 0.15)) (justify left bottom mirror))
    )
    (fp_text user "${REFERENCE}" (at -0.932 -3.168 90) (layer "B.Fab") hide
        (effects (font (size 0.7 0.7) (thickness 0.15)) (justify left bottom mirror))
    )
    (fp_text user "Author: Antmicro" (at -0.932 -4.17 90) (layer "B.Fab") hide
        (effects (font (size 0.7 0.7) (thickness 0.15)) (justify left bottom mirror))
    )
    (fp_text user "License: Apache-2.0" (at -0.932 -5.17 90) (layer "B.Fab") hide
        (effects (font (size 0.7 0.7) (thickness 0.15)) (justify left bottom mirror))
    )
    (fp_rect (start -0.94 0.47) (end 0.94 -0.47)
      (stroke (width 0.05) (type solid)) (fill none) (layer "B.CrtYd"))
    (fp_rect (start -0.499 0.249) (end 0.499 -0.249)
      (stroke (width 0.15) (type solid)) (fill none) (layer "B.Fab"))
    (pad "1" smd roundrect (at -0.484 0 270) (size 0.59 0.64) (layers "B.Cu" "B.Paste" "B.Mask") (roundrect_rratio 0.25)
      (net 15 "PS_3V3") (pintype "passive"))
    (pad "2" smd roundrect (at 0.484 0 270) (size 0.59 0.64) (layers "B.Cu" "B.Paste" "B.Mask") (roundrect_rratio 0.25)
      (net 131 "Net-(Q2-G)") (pintype "passive"))
  )
	(footprint "kria-k26-devboard-footprints:R_0402_1005Metric" (layer "B.Cu")
    (at 123.15 146.55 -90)
    (descr "Resistor SMD 0402")
    (tags "resistor SMD 0402")
    (property "Author" "Antmicro")
    (property "License" "Apache-2.0")
    (property "MPN" "CR0402-FX-1002GLF")
    (property "Manufacturer" "Bourns")
    (property "Sheetfile" "sd-3-card.kicad_sch")
    (property "Sheetname" "SD 3.0 card")
    (property "Tolerance" "1%")
    (property "Val" "10k")
    (property "ki_description" "10k resistor in 0402 package with 1% tolerance")
    (attr smd)
    (fp_text reference "R16" (at 0.87 -0.41 90) (layer "B.SilkS")
        (effects (font (size 0.7 0.7) (thickness 0.15)) (justify left bottom mirror))
    )
    (fp_text value "R_10k_0402" (at 0 -1.4 90) (layer "B.Fab") hide
        (effects (font (size 0.7 0.7) (thickness 0.15)) (justify left bottom mirror))
    )
    (fp_text user "${REFERENCE}" (at -0.95 -3.168 90) (layer "B.Fab") hide
        (effects (font (size 0.7 0.7) (thickness 0.15)) (justify left bottom mirror))
    )
    (fp_text user "Author: Antmicro" (at -0.95 -4.169 90) (layer "B.Fab") hide
        (effects (font (size 0.7 0.7) (thickness 0.15)) (justify left bottom mirror))
    )
    (fp_text user "License: Apache-2.0" (at -0.95 -5.169 90) (layer "B.Fab") hide
        (effects (font (size 0.7 0.7) (thickness 0.15)) (justify left bottom mirror))
    )
    (fp_rect (start -0.93 0.47) (end 0.93 -0.47)
      (stroke (width 0.05) (type solid)) (fill none) (layer "B.CrtYd"))
    (fp_rect (start -0.5 0.25) (end 0.5 -0.25)
      (stroke (width 0.15) (type solid)) (fill none) (layer "B.Fab"))
    (pad "1" smd roundrect (at -0.485 0 270) (size 0.59 0.64) (layers "B.Cu" "B.Paste" "B.Mask") (roundrect_rratio 0.25)
      (net 15 "PS_3V3") (pintype "passive"))
    (pad "2" smd roundrect (at 0.485 0 270) (size 0.59 0.64) (layers "B.Cu" "B.Paste" "B.Mask") (roundrect_rratio 0.25)
      (net 131 "Net-(Q2-G)") (pintype "passive"))
  )
	(footprint "kria-k26-devboard-footprints:C_0402_1005Metric" (layer "B.Cu")
    (at 125.05 146.55 90)
    (descr "Capacitor SMD 0402")
    (tags "capacitor SMD 0402")
    (property "Author" "Antmicro")
    (property "Dielectric" "")
    (property "License" "Apache-2.0")
    (property "MPN" "C1005X5R1E474M050BB")
    (property "Manufacturer" "TDK")
    (property "Sheetfile" "sd-3-card.kicad_sch")
    (property "Sheetname" "SD 3.0 card")
    (property "Val" "470n")
    (property "Voltage" "")
    (property "ki_description" " ")
    (attr smd)
    (fp_text reference "C18" (at -0.87 0.42 270) (layer "B.SilkS")
        (effects (font (size 0.7 0.7) (thickness 0.15)) (justify left bottom mirror))
    )
    (fp_text value "C_470n_0402" (at 0 -1.4 270) (layer "B.Fab") hide
        (effects (font (size 0.7 0.7) (thickness 0.15)) (justify left bottom mirror))
    )
    (fp_text user "${REFERENCE}" (at -0.932 -3.168 270) (layer "B.Fab") hide
        (effects (font (size 0.7 0.7) (thickness 0.15)) (justify left bottom mirror))
    )
    (fp_text user "License: Apache-2.0" (at -0.932 -5.17 270) (layer "B.Fab") hide
        (effects (font (size 0.7 0.7) (thickness 0.15)) (justify left bottom mirror))
    )
    (fp_text user "Author: Antmicro" (at -0.932 -4.17 270) (layer "B.Fab") hide
        (effects (font (size 0.7 0.7) (thickness 0.15)) (justify left bottom mirror))
    )
    (fp_rect (start -0.94 0.47) (end 0.94 -0.47)
      (stroke (width 0.05) (type solid)) (fill none) (layer "B.CrtYd"))
    (fp_rect (start -0.499 0.249) (end 0.499 -0.249)
      (stroke (width 0.15) (type solid)) (fill none) (layer "B.Fab"))
    (pad "1" smd roundrect (at -0.484 0 90) (size 0.59 0.64) (layers "B.Cu" "B.Paste" "B.Mask") (roundrect_rratio 0.25)
      (net 131 "Net-(Q2-G)") (pintype "passive"))
    (pad "2" smd roundrect (at 0.484 0 90) (size 0.59 0.64) (layers "B.Cu" "B.Paste" "B.Mask") (roundrect_rratio 0.25)
      (net 317 "/SD 3.0 card/SD_VDD") (pintype "passive"))
  )
	(footprint "kria-k26-devboard-footprints:C_0402_1005Metric" (layer "B.Cu")
    (at 130.025 75.105 -90)
    (descr "Capacitor SMD 0402")
    (tags "capacitor SMD 0402")
    (property "Author" "Antmicro")
    (property "Dielectric" "X5R")
    (property "License" "Apache-2.0")
    (property "MPN" "GRM155R61H104KE14D")
    (property "Manufacturer" "Murata")
    (property "Sheetfile" "usb.kicad_sch")
    (property "Sheetname" "USB")
    (property "Val" "100n")
    (property "Voltage" "50V")
    (property "ki_description" " ")
    (attr smd)
    (fp_text reference "C66" (at 0.845 -0.385 90) (layer "B.SilkS")
        (effects (font (size 0.7 0.7) (thickness 0.15)) (justify left bottom mirror))
    )
    (fp_text value "C_100n_0402" (at 0 -1.4 90) (layer "B.Fab") hide
        (effects (font (size 0.7 0.7) (thickness 0.15)) (justify left bottom mirror))
    )
    (fp_text user "${REFERENCE}" (at -0.932 -3.168 90) (layer "B.Fab") hide
        (effects (font (size 0.7 0.7) (thickness 0.15)) (justify left bottom mirror))
    )
    (fp_text user "Author: Antmicro" (at -0.932 -4.17 90) (layer "B.Fab") hide
        (effects (font (size 0.7 0.7) (thickness 0.15)) (justify left bottom mirror))
    )
    (fp_text user "License: Apache-2.0" (at -0.932 -5.17 90) (layer "B.Fab") hide
        (effects (font (size 0.7 0.7) (thickness 0.15)) (justify left bottom mirror))
    )
    (fp_rect (start -0.94 0.47) (end 0.94 -0.47)
      (stroke (width 0.05) (type solid)) (fill none) (layer "B.CrtYd"))
    (fp_rect (start -0.499 0.249) (end 0.499 -0.249)
      (stroke (width 0.15) (type solid)) (fill none) (layer "B.Fab"))
    (pad "1" smd roundrect (at -0.484 0 270) (size 0.59 0.64) (layers "B.Cu" "B.Paste" "B.Mask") (roundrect_rratio 0.25)
      (net 278 "/USB/USB1_TX_C_N") (pintype "passive"))
    (pad "2" smd roundrect (at 0.484 0 270) (size 0.59 0.64) (layers "B.Cu" "B.Paste" "B.Mask") (roundrect_rratio 0.25)
      (net 60 "/USB/USB1_TX_N") (pintype "passive"))
  )
	(footprint "kria-k26-devboard-footprints:C_0402_1005Metric" (layer "B.Cu")
    (at 130.975 75.105 -90)
    (descr "Capacitor SMD 0402")
    (tags "capacitor SMD 0402")
    (property "Author" "Antmicro")
    (property "Dielectric" "X5R")
    (property "License" "Apache-2.0")
    (property "MPN" "GRM155R61H104KE14D")
    (property "Manufacturer" "Murata")
    (property "Sheetfile" "usb.kicad_sch")
    (property "Sheetname" "USB")
    (property "Val" "100n")
    (property "Voltage" "50V")
    (property "ki_description" " ")
    (attr smd)
    (fp_text reference "C67" (at 0.845 -0.385 90) (layer "B.SilkS")
        (effects (font (size 0.7 0.7) (thickness 0.15)) (justify left bottom mirror))
    )
    (fp_text value "C_100n_0402" (at 0 -1.4 90) (layer "B.Fab") hide
        (effects (font (size 0.7 0.7) (thickness 0.15)) (justify left bottom mirror))
    )
    (fp_text user "${REFERENCE}" (at -0.932 -3.168 90) (layer "B.Fab") hide
        (effects (font (size 0.7 0.7) (thickness 0.15)) (justify left bottom mirror))
    )
    (fp_text user "License: Apache-2.0" (at -0.932 -5.17 90) (layer "B.Fab") hide
        (effects (font (size 0.7 0.7) (thickness 0.15)) (justify left bottom mirror))
    )
    (fp_text user "Author: Antmicro" (at -0.932 -4.17 90) (layer "B.Fab") hide
        (effects (font (size 0.7 0.7) (thickness 0.15)) (justify left bottom mirror))
    )
    (fp_rect (start -0.94 0.47) (end 0.94 -0.47)
      (stroke (width 0.05) (type solid)) (fill none) (layer "B.CrtYd"))
    (fp_rect (start -0.499 0.249) (end 0.499 -0.249)
      (stroke (width 0.15) (type solid)) (fill none) (layer "B.Fab"))
    (pad "1" smd roundrect (at -0.484 0 270) (size 0.59 0.64) (layers "B.Cu" "B.Paste" "B.Mask") (roundrect_rratio 0.25)
      (net 279 "/USB/USB1_TX_C_P") (pintype "passive"))
    (pad "2" smd roundrect (at 0.484 0 270) (size 0.59 0.64) (layers "B.Cu" "B.Paste" "B.Mask") (roundrect_rratio 0.25)
      (net 61 "/USB/USB1_TX_P") (pintype "passive"))
  )
	(footprint "kria-k26-devboard-footprints:C_0402_1005Metric" (layer "B.Cu")
    (at 92.45 129.675)
    (descr "Capacitor SMD 0402")
    (tags "capacitor SMD 0402")
    (property "Author" "Antmicro")
    (property "Dielectric" "")
    (property "License" "Apache-2.0")
    (property "MPN" "GRM155R61A475MEAAD")
    (property "Manufacturer" "Murata")
    (property "Sheetfile" "k26_som.kicad_sch")
    (property "Sheetname" "Xilinx K26 SOM")
    (property "Val" "4u7")
    (property "Voltage" "")
    (property "ki_description" " ")
    (attr smd)
    (fp_text reference "C127" (at 3.8 0.355 180) (layer "B.SilkS")
        (effects (font (size 0.7 0.7) (thickness 0.15)) (justify left bottom mirror))
    )
    (fp_text value "C_4u7_0402" (at 0 -1.4 180) (layer "B.Fab") hide
        (effects (font (size 0.7 0.7) (thickness 0.15)) (justify left bottom mirror))
    )
    (fp_text user "License: Apache-2.0" (at -0.932 -5.17 180) (layer "B.Fab") hide
        (effects (font (size 0.7 0.7) (thickness 0.15)) (justify left bottom mirror))
    )
    (fp_text user "Author: Antmicro" (at -0.932 -4.17 180) (layer "B.Fab") hide
        (effects (font (size 0.7 0.7) (thickness 0.15)) (justify left bottom mirror))
    )
    (fp_text user "${REFERENCE}" (at -0.932 -3.168 180) (layer "B.Fab") hide
        (effects (font (size 0.7 0.7) (thickness 0.15)) (justify left bottom mirror))
    )
    (fp_rect (start -0.94 0.47) (end 0.94 -0.47)
      (stroke (width 0.05) (type solid)) (fill none) (layer "B.CrtYd"))
    (fp_rect (start -0.499 0.249) (end 0.499 -0.249)
      (stroke (width 0.15) (type solid)) (fill none) (layer "B.Fab"))
    (pad "1" smd roundrect (at -0.484 0) (size 0.59 0.64) (layers "B.Cu" "B.Paste" "B.Mask") (roundrect_rratio 0.25)
      (net 20 "PL_3V3") (pintype "passive"))
    (pad "2" smd roundrect (at 0.484 0) (size 0.59 0.64) (layers "B.Cu" "B.Paste" "B.Mask") (roundrect_rratio 0.25)
      (net 1 "GND") (pintype "passive"))
  )
	(footprint "kria-k26-devboard-footprints:C_0402_1005Metric" (layer "B.Cu")
    (at 138.31 93.85 -90)
    (descr "Capacitor SMD 0402")
    (tags "capacitor SMD 0402")
    (property "Author" "Antmicro")
    (property "Dielectric" "X5R")
    (property "License" "Apache-2.0")
    (property "MPN" "GRM155R61H104KE14D")
    (property "Manufacturer" "Murata")
    (property "Sheetfile" "dc-dc-conventers.kicad_sch")
    (property "Sheetname" "DC/DC conventers")
    (property "Val" "100n")
    (property "Voltage" "50V")
    (property "ki_description" " ")
    (attr smd)
    (fp_text reference "C210" (at 3.158 -0.365 -90) (layer "B.SilkS")
        (effects (font (size 0.7 0.7) (thickness 0.15)) (justify left bottom mirror))
    )
    (fp_text value "C_100n_0402" (at 0 -1.4 90) (layer "B.Fab") hide
        (effects (font (size 0.7 0.7) (thickness 0.15)) (justify left bottom mirror))
    )
    (fp_text user "Author: Antmicro" (at -0.932 -4.17 90) (layer "B.Fab") hide
        (effects (font (size 0.7 0.7) (thickness 0.15)) (justify left bottom mirror))
    )
    (fp_text user "${REFERENCE}" (at -0.932 -3.168 90) (layer "B.Fab") hide
        (effects (font (size 0.7 0.7) (thickness 0.15)) (justify left bottom mirror))
    )
    (fp_text user "License: Apache-2.0" (at -0.932 -5.17 90) (layer "B.Fab") hide
        (effects (font (size 0.7 0.7) (thickness 0.15)) (justify left bottom mirror))
    )
    (fp_rect (start -0.94 0.47) (end 0.94 -0.47)
      (stroke (width 0.05) (type solid)) (fill none) (layer "B.CrtYd"))
    (fp_rect (start -0.499 0.249) (end 0.499 -0.249)
      (stroke (width 0.15) (type solid)) (fill none) (layer "B.Fab"))
    (pad "1" smd roundrect (at -0.484 0 270) (size 0.59 0.64) (layers "B.Cu" "B.Paste" "B.Mask") (roundrect_rratio 0.25)
      (net 323 "Net-(U53-BST)") (pintype "passive"))
    (pad "2" smd roundrect (at 0.484 0 270) (size 0.59 0.64) (layers "B.Cu" "B.Paste" "B.Mask") (roundrect_rratio 0.25)
      (net 256 "/Power Supply/DC/DC conventers/SW_PS_1V0") (pintype "passive"))
  )
	(footprint "kria-k26-devboard-footprints:C_0402_1005Metric" (layer "B.Cu")
    (at 142.889035 94.404089 -90)
    (descr "Capacitor SMD 0402")
    (tags "capacitor SMD 0402")
    (property "Author" "Antmicro")
    (property "Dielectric" "X7R")
    (property "License" "Apache-2.0")
    (property "MPN" "GRM155R71H103KA88D")
    (property "Manufacturer" "Murata")
    (property "Sheetfile" "eth.kicad_sch")
    (property "Sheetname" "Ethernet")
    (property "Val" "10n")
    (property "Voltage" "50V")
    (property "ki_description" " ")
    (attr smd)
    (fp_text reference "C113" (at 0.945911 -0.360965 90) (layer "B.SilkS")
        (effects (font (size 0.7 0.7) (thickness 0.15)) (justify left bottom mirror))
    )
    (fp_text value "C_10n_0402" (at 0 -1.4 90) (layer "B.Fab") hide
        (effects (font (size 0.7 0.7) (thickness 0.15)) (justify left bottom mirror))
    )
    (fp_text user "License: Apache-2.0" (at -0.932 -5.17 90) (layer "B.Fab") hide
        (effects (font (size 0.7 0.7) (thickness 0.15)) (justify left bottom mirror))
    )
    (fp_text user "${REFERENCE}" (at -0.932 -3.168 90) (layer "B.Fab") hide
        (effects (font (size 0.7 0.7) (thickness 0.15)) (justify left bottom mirror))
    )
    (fp_text user "Author: Antmicro" (at -0.932 -4.17 90) (layer "B.Fab") hide
        (effects (font (size 0.7 0.7) (thickness 0.15)) (justify left bottom mirror))
    )
    (fp_rect (start -0.94 0.47) (end 0.94 -0.47)
      (stroke (width 0.05) (type solid)) (fill none) (layer "B.CrtYd"))
    (fp_rect (start -0.499 0.249) (end 0.499 -0.249)
      (stroke (width 0.15) (type solid)) (fill none) (layer "B.Fab"))
    (pad "1" smd roundrect (at -0.484 0 270) (size 0.59 0.64) (layers "B.Cu" "B.Paste" "B.Mask") (roundrect_rratio 0.25)
      (net 19 "PS_1V0") (pintype "passive"))
    (pad "2" smd roundrect (at 0.484 0 270) (size 0.59 0.64) (layers "B.Cu" "B.Paste" "B.Mask") (roundrect_rratio 0.25)
      (net 1 "GND") (pintype "passive"))
  )
	(footprint "kria-k26-devboard-footprints:C_0603_1608Metric" (layer "B.Cu")
    (at 141.654035 94.669089 90)
    (descr "Capacitor SMD 0603")
    (tags "capacitor 0603")
    (property "Author" "Antmicro")
    (property "License" "Apache-2.0")
    (property "MPN" "GRM188R61A106KE69D")
    (property "Manufacturer" "Murata")
    (property "Sheetfile" "eth.kicad_sch")
    (property "Sheetname" "Ethernet")
    (property "Val" "10u")
    (property "Voltage" "")
    (property "ki_description" " ")
    (attr smd)
    (fp_text reference "C114" (at -1.220911 0.445965 270) (layer "B.SilkS")
        (effects (font (size 0.7 0.7) (thickness 0.15)) (justify left bottom mirror))
    )
    (fp_text value "C_10u_0603" (at 0 -1.6 270) (layer "B.Fab") hide
        (effects (font (size 0.7 0.7) (thickness 0.15)) (justify left bottom mirror))
    )
    (fp_text user "Author: Antmicro" (at -1.682 -4.894 270) (layer "B.Fab") hide
        (effects (font (size 0.7 0.7) (thickness 0.15)) (justify left bottom mirror))
    )
    (fp_text user "License: Apache-2.0" (at -1.682 -5.895 270) (layer "B.Fab") hide
        (effects (font (size 0.7 0.7) (thickness 0.15)) (justify left bottom mirror))
    )
    (fp_text user "${REFERENCE}" (at -1.682 -3.895 270) (layer "B.Fab") hide
        (effects (font (size 0.7 0.7) (thickness 0.15)) (justify left bottom mirror))
    )
    (fp_line (start -0.3 -0.3) (end 0.3 -0.3)
      (stroke (width 0.15) (type solid)) (layer "B.SilkS"))
    (fp_line (start -0.3 0.3) (end 0.3 0.3)
      (stroke (width 0.15) (type solid)) (layer "B.SilkS"))
    (fp_rect (start -1.24 0.7) (end 1.24 -0.7)
      (stroke (width 0.05) (type solid)) (fill none) (layer "B.CrtYd"))
    (fp_rect (start -0.8 0.4) (end 0.8 -0.4)
      (stroke (width 0.15) (type solid)) (fill none) (layer "B.Fab"))
    (pad "1" smd roundrect (at -0.7 0 90) (size 0.6 0.8) (layers "B.Cu" "B.Paste" "B.Mask") (roundrect_rratio 0.2)
      (net 1 "GND") (pintype "passive"))
    (pad "2" smd roundrect (at 0.7 0 90) (size 0.6 0.8) (layers "B.Cu" "B.Paste" "B.Mask") (roundrect_rratio 0.2)
      (net 19 "PS_1V0") (pintype "passive"))
  )
	(footprint "kria-k26-devboard-footprints:C_0402_1005Metric" (layer "B.Cu")
    (at 127.66 86.12 180)
    (descr "Capacitor SMD 0402")
    (tags "capacitor SMD 0402")
    (property "Author" "Antmicro")
    (property "Dielectric" "X5R")
    (property "License" "Apache-2.0")
    (property "MPN" "GRM155R61H104KE14D")
    (property "Manufacturer" "Murata")
    (property "Sheetfile" "usb.kicad_sch")
    (property "Sheetname" "USB")
    (property "Val" "100n")
    (property "Voltage" "50V")
    (property "ki_description" " ")
    (attr smd)
    (fp_text reference "C44" (at 0.901 -0.38) (layer "B.SilkS")
        (effects (font (size 0.7 0.7) (thickness 0.15)) (justify left bottom mirror))
    )
    (fp_text value "C_100n_0402" (at 0 -1.4) (layer "B.Fab") hide
        (effects (font (size 0.7 0.7) (thickness 0.15)) (justify left bottom mirror))
    )
    (fp_text user "${REFERENCE}" (at -0.932 -3.168) (layer "B.Fab") hide
        (effects (font (size 0.7 0.7) (thickness 0.15)) (justify left bottom mirror))
    )
    (fp_text user "Author: Antmicro" (at -0.932 -4.17) (layer "B.Fab") hide
        (effects (font (size 0.7 0.7) (thickness 0.15)) (justify left bottom mirror))
    )
    (fp_text user "License: Apache-2.0" (at -0.932 -5.17) (layer "B.Fab") hide
        (effects (font (size 0.7 0.7) (thickness 0.15)) (justify left bottom mirror))
    )
    (fp_rect (start -0.94 0.47) (end 0.94 -0.47)
      (stroke (width 0.05) (type solid)) (fill none) (layer "B.CrtYd"))
    (fp_rect (start -0.499 0.249) (end 0.499 -0.249)
      (stroke (width 0.15) (type solid)) (fill none) (layer "B.Fab"))
    (pad "1" smd roundrect (at -0.484 0 180) (size 0.59 0.64) (layers "B.Cu" "B.Paste" "B.Mask") (roundrect_rratio 0.25)
      (net 18 "PS_1V2") (pintype "passive"))
    (pad "2" smd roundrect (at 0.484 0 180) (size 0.59 0.64) (layers "B.Cu" "B.Paste" "B.Mask") (roundrect_rratio 0.25)
      (net 1 "GND") (pintype "passive"))
  )
)
